(kicad_pcb
	(version 20241229)
	(generator "pcbnew")
	(generator_version "9.0")
	(general
		(thickness 1.599998)
		(legacy_teardrops no)
	)
	(paper "A4")
	(title_block
		(title "Artix - Datacenter Secure Control Module (DC-SCM)")
		(date "2024-11-06")
		(rev "1.1.3")
		(comment 9 "footprints 52-56 of 544")
	)
	(layers
		(0 "F.Cu" signal)
		(4 "In1.Cu" signal)
		(6 "In2.Cu" signal)
		(8 "In3.Cu" signal)
		(10 "In4.Cu" signal)
		(12 "In5.Cu" signal)
		(14 "In6.Cu" signal)
		(2 "B.Cu" signal)
		(9 "F.Adhes" user "F.Adhesive")
		(11 "B.Adhes" user "B.Adhesive")
		(13 "F.Paste" user)
		(15 "B.Paste" user)
		(5 "F.SilkS" user "F.Silkscreen")
		(7 "B.SilkS" user "B.Silkscreen")
		(1 "F.Mask" user)
		(3 "B.Mask" user)
		(17 "Dwgs.User" user "User.Drawings")
		(19 "Cmts.User" user "User.Comments")
		(21 "Eco1.User" user "User.Eco1")
		(23 "Eco2.User" user "User.Eco2")
		(25 "Edge.Cuts" user)
		(27 "Margin" user)
		(31 "F.CrtYd" user "F.Courtyard")
		(29 "B.CrtYd" user "B.Courtyard")
		(35 "F.Fab" user)
		(33 "B.Fab" user)
	)
	(footprint "antmicro-footprints:C_0402_1005Metric"
		(layer "F.Cu")
		(at 91.545 81.825 90)
		(descr "Capacitor SMD 0402")
		(tags "capacitor SMD 0402")
		(property "Reference" "C81"
			(at -1.075 2.355 90)
			(layer "F.SilkS")
			(effects
				(font
					(size 0.7 0.7)
					(thickness 0.15)
				)
				(justify left bottom)
			)
		)
		(property "Value" "C_120p_0402"
			(at 0 1.4 90)
			(layer "F.Fab")
			(effects
				(font
					(size 0.7 0.7)
					(thickness 0.15)
				)
				(justify left bottom)
			)
		)
		(property "Datasheet" "https://www.kemet.com/en/us/capacitors/product/C0402C121J5GACTU.html"
			(at 0 0 90)
			(layer "F.Fab")
			(hide yes)
			(effects
				(font
					(size 1.27 1.27)
					(thickness 0.15)
				)
			)
		)
		(property "Description" "120 pF ±2% 100V Ceramic Capacitor C0G, NP0 0402 (1005 Metric)"
			(at 0 0 90)
			(layer "F.Fab")
			(hide yes)
			(effects
				(font
					(size 1.27 1.27)
					(thickness 0.15)
				)
			)
		)
		(property "Author" "Antmicro"
			(at 173.37 -9.72 0)
			(layer "F.Fab")
			(hide yes)
			(effects
				(font
					(size 1 1)
					(thickness 0.15)
				)
			)
		)
		(property "Dielectric" "C0G"
			(at 173.37 -9.72 0)
			(layer "F.Fab")
			(hide yes)
			(effects
				(font
					(size 1 1)
					(thickness 0.15)
				)
			)
		)
		(property "License" "Apache-2.0"
			(at 173.37 -9.72 0)
			(layer "F.Fab")
			(hide yes)
			(effects
				(font
					(size 1 1)
					(thickness 0.15)
				)
			)
		)
		(property "MPN" "C0402C121J5GACTU"
			(at 173.37 -9.72 0)
			(layer "F.Fab")
			(hide yes)
			(effects
				(font
					(size 1 1)
					(thickness 0.15)
				)
			)
		)
		(property "Manufacturer" "KEMET"
			(at 173.37 -9.72 0)
			(layer "F.Fab")
			(hide yes)
			(effects
				(font
					(size 1 1)
					(thickness 0.15)
				)
			)
		)
		(property "Val" "120p"
			(at 173.37 -9.72 0)
			(layer "F.Fab")
			(hide yes)
			(effects
				(font
					(size 1 1)
					(thickness 0.15)
				)
			)
		)
		(property "Voltage" "100V"
			(at 173.37 -9.72 0)
			(layer "F.Fab")
			(hide yes)
			(effects
				(font
					(size 1 1)
					(thickness 0.15)
				)
			)
		)
		(sheetname "/Power supply/")
		(sheetfile "power-supply.kicad_sch")
		(attr smd)
		(fp_rect
			(start -0.925 -0.47)
			(end 0.925 0.47)
			(stroke
				(width 0.05)
				(type default)
			)
			(fill no)
			(layer "F.CrtYd")
		)
		(fp_line
			(start 0.504 -0.25)
			(end 0.504 0.248)
			(stroke
				(width 0.15)
				(type solid)
			)
			(layer "F.Fab")
		)
		(fp_line
			(start -0.494 -0.25)
			(end 0.504 -0.25)
			(stroke
				(width 0.15)
				(type solid)
			)
			(layer "F.Fab")
		)
		(fp_line
			(start 0.504 0.248)
			(end -0.494 0.248)
			(stroke
				(width 0.15)
				(type solid)
			)
			(layer "F.Fab")
		)
		(fp_line
			(start -0.494 0.248)
			(end -0.494 -0.25)
			(stroke
				(width 0.15)
				(type solid)
			)
			(layer "F.Fab")
		)
		(pad "1" smd roundrect
			(at -0.48 0 90)
			(size 0.59 0.64)
			(layers "F.Cu" "F.Mask" "F.Paste")
			(roundrect_rratio 0.25)
			(net 195 "Net-(U12-FB)")
			(pintype "passive")
		)
		(pad "2" smd roundrect
			(at 0.48 0 90)
			(size 0.59 0.64)
			(layers "F.Cu" "F.Mask" "F.Paste")
			(roundrect_rratio 0.25)
			(net 276 "Net-(C81-Pad2)")
			(pintype "passive")
		)
	)
	(footprint "antmicro-footprints:C_0603_1608Metric"
		(layer "F.Cu")
		(at 85.075 81.8 -90)
		(descr "Capacitor SMD 0603")
		(tags "capacitor 0603")
		(property "Reference" "C77"
			(at 2.2 0.575 270)
			(layer "F.SilkS")
			(effects
				(font
					(size 0.7 0.7)
					(thickness 0.15)
				)
				(justify left bottom)
			)
		)
		(property "Value" "C_10u_0603"
			(at 0 1.6 270)
			(layer "F.Fab")
			(effects
				(font
					(size 0.7 0.7)
					(thickness 0.15)
				)
				(justify left bottom)
			)
		)
		(property "Datasheet" "https://www.murata.com/products/productdetail?partno=GRM188R61A106KE69%23"
			(at 0 0 270)
			(layer "F.Fab")
			(hide yes)
			(effects
				(font
					(size 1.27 1.27)
					(thickness 0.15)
				)
			)
		)
		(property "Description" "SMD Multilayer Ceramic Capacitor, 10 µF, 10 V, 0603 [1608 Metric], ± 10%, X5R, GRM Series"
			(at 0 0 270)
			(layer "F.Fab")
			(hide yes)
			(effects
				(font
					(size 1.27 1.27)
					(thickness 0.15)
				)
			)
		)
		(property "Author" "Antmicro"
			(at 3.275 166.875 0)
			(layer "F.Fab")
			(hide yes)
			(effects
				(font
					(size 1 1)
					(thickness 0.15)
				)
			)
		)
		(property "Dielectric" "template_dielectric"
			(at 3.275 166.875 0)
			(layer "F.Fab")
			(hide yes)
			(effects
				(font
					(size 1 1)
					(thickness 0.15)
				)
			)
		)
		(property "License" "Apache-2.0"
			(at 3.275 166.875 0)
			(layer "F.Fab")
			(hide yes)
			(effects
				(font
					(size 1 1)
					(thickness 0.15)
				)
			)
		)
		(property "MPN" "GRM188R61A106KE69D"
			(at 3.275 166.875 0)
			(layer "F.Fab")
			(hide yes)
			(effects
				(font
					(size 1 1)
					(thickness 0.15)
				)
			)
		)
		(property "Manufacturer" "Murata"
			(at 3.275 166.875 0)
			(layer "F.Fab")
			(hide yes)
			(effects
				(font
					(size 1 1)
					(thickness 0.15)
				)
			)
		)
		(property "Val" "10u"
			(at 3.275 166.875 0)
			(layer "F.Fab")
			(hide yes)
			(effects
				(font
					(size 1 1)
					(thickness 0.15)
				)
			)
		)
		(property "Voltage" ""
			(at 3.275 166.875 0)
			(layer "F.Fab")
			(hide yes)
			(effects
				(font
					(size 1 1)
					(thickness 0.15)
				)
			)
		)
		(sheetname "/Power supply/")
		(sheetfile "power-supply.kicad_sch")
		(attr smd)
		(fp_line
			(start -0.15 0.4)
			(end 0.15 0.4)
			(stroke
				(width 0.15)
				(type solid)
			)
			(layer "F.SilkS")
		)
		(fp_line
			(start -0.15 -0.4)
			(end 0.15 -0.4)
			(stroke
				(width 0.15)
				(type solid)
			)
			(layer "F.SilkS")
		)
		(fp_rect
			(start -1.25 -0.65)
			(end 1.25 0.65)
			(stroke
				(width 0.05)
				(type solid)
			)
			(fill no)
			(layer "F.CrtYd")
		)
		(fp_rect
			(start -0.8 -0.4)
			(end 0.8 0.4)
			(stroke
				(width 0.15)
				(type solid)
			)
			(fill no)
			(layer "F.Fab")
		)
		(pad "1" smd roundrect
			(at -0.7 0 270)
			(size 0.8 1)
			(layers "F.Cu" "F.Mask" "F.Paste")
			(roundrect_rratio 0.2)
			(net 1 "GND")
			(pintype "passive")
		)
		(pad "2" smd roundrect
			(at 0.7 0 270)
			(size 0.8 1)
			(layers "F.Cu" "F.Mask" "F.Paste")
			(roundrect_rratio 0.2)
			(net 4 "VCC5V0")
			(pintype "passive")
		)
	)
	(footprint "antmicro-footprints:C_0402_1005Metric"
		(layer "F.Cu")
		(at 85.905 85.385 180)
		(descr "Capacitor SMD 0402")
		(tags "capacitor SMD 0402")
		(property "Reference" "C90"
			(at -2.995 -0.315 0)
			(layer "F.SilkS")
			(effects
				(font
					(size 0.7 0.7)
					(thickness 0.15)
				)
				(justify right bottom)
			)
		)
		(property "Value" "C_10u_0402"
			(at 0 1.4 0)
			(layer "F.Fab")
			(effects
				(font
					(size 0.7 0.7)
					(thickness 0.15)
				)
				(justify right bottom)
			)
		)
		(property "Datasheet" "https://www.yageo.com/en/Chart/Download/pdf/CC0402MRX5R5BB106"
			(at 0 0 180)
			(layer "F.Fab")
			(hide yes)
			(effects
				(font
					(size 1.27 1.27)
					(thickness 0.15)
				)
			)
		)
		(property "Description" "SMD Multilayer Ceramic Capacitor, 10 µF, 6.3 V, 0402 [1005 Metric], ± 20%, X5R, CC Series"
			(at 0 0 180)
			(layer "F.Fab")
			(hide yes)
			(effects
				(font
					(size 1.27 1.27)
					(thickness 0.15)
				)
			)
		)
		(property "Author" "Antmicro"
			(at 171.81 170.77 0)
			(layer "F.Fab")
			(hide yes)
			(effects
				(font
					(size 1 1)
					(thickness 0.15)
				)
			)
		)
		(property "Dielectric" ""
			(at 171.81 170.77 0)
			(layer "F.Fab")
			(hide yes)
			(effects
				(font
					(size 1 1)
					(thickness 0.15)
				)
			)
		)
		(property "License" "Apache-2.0"
			(at 171.81 170.77 0)
			(layer "F.Fab")
			(hide yes)
			(effects
				(font
					(size 1 1)
					(thickness 0.15)
				)
			)
		)
		(property "MPN" "CC0402MRX5R5BB106"
			(at 171.81 170.77 0)
			(layer "F.Fab")
			(hide yes)
			(effects
				(font
					(size 1 1)
					(thickness 0.15)
				)
			)
		)
		(property "Manufacturer" "YAGEO"
			(at 171.81 170.77 0)
			(layer "F.Fab")
			(hide yes)
			(effects
				(font
					(size 1 1)
					(thickness 0.15)
				)
			)
		)
		(property "Val" "10u"
			(at 171.81 170.77 0)
			(layer "F.Fab")
			(hide yes)
			(effects
				(font
					(size 1 1)
					(thickness 0.15)
				)
			)
		)
		(property "Voltage" ""
			(at 171.81 170.77 0)
			(layer "F.Fab")
			(hide yes)
			(effects
				(font
					(size 1 1)
					(thickness 0.15)
				)
			)
		)
		(sheetname "/Power supply/")
		(sheetfile "power-supply.kicad_sch")
		(attr smd)
		(fp_rect
			(start -0.925 -0.47)
			(end 0.925 0.47)
			(stroke
				(width 0.05)
				(type default)
			)
			(fill no)
			(layer "F.CrtYd")
		)
		(fp_line
			(start 0.504 0.248)
			(end -0.494 0.248)
			(stroke
				(width 0.15)
				(type solid)
			)
			(layer "F.Fab")
		)
		(fp_line
			(start 0.504 -0.25)
			(end 0.504 0.248)
			(stroke
				(width 0.15)
				(type solid)
			)
			(layer "F.Fab")
		)
		(fp_line
			(start -0.494 0.248)
			(end -0.494 -0.25)
			(stroke
				(width 0.15)
				(type solid)
			)
			(layer "F.Fab")
		)
		(fp_line
			(start -0.494 -0.25)
			(end 0.504 -0.25)
			(stroke
				(width 0.15)
				(type solid)
			)
			(layer "F.Fab")
		)
		(pad "1" smd roundrect
			(at -0.48 0 180)
			(size 0.59 0.64)
			(layers "F.Cu" "F.Mask" "F.Paste")
			(roundrect_rratio 0.25)
			(net 1 "GND")
			(pintype "passive")
		)
		(pad "2" smd roundrect
			(at 0.48 0 180)
			(size 0.59 0.64)
			(layers "F.Cu" "F.Mask" "F.Paste")
			(roundrect_rratio 0.25)
			(net 277 "Net-(C82-Pad2)")
			(pintype "passive")
		)
	)
	(footprint "antmicro-footprints:C_0603_1608Metric"
		(layer "F.Cu")
		(at 85.175 89.175 -90)
		(descr "Capacitor SMD 0603")
		(tags "capacitor 0603")
		(property "Reference" "C78"
			(at 2.025 0.575 270)
			(layer "F.SilkS")
			(effects
				(font
					(size 0.7 0.7)
					(thickness 0.15)
				)
				(justify left bottom)
			)
		)
		(property "Value" "C_10u_0603"
			(at 0 1.6 270)
			(layer "F.Fab")
			(effects
				(font
					(size 0.7 0.7)
					(thickness 0.15)
				)
				(justify left bottom)
			)
		)
		(property "Datasheet" "https://www.murata.com/products/productdetail?partno=GRM188R61A106KE69%23"
			(at 0 0 270)
			(layer "F.Fab")
			(hide yes)
			(effects
				(font
					(size 1.27 1.27)
					(thickness 0.15)
				)
			)
		)
		(property "Description" "SMD Multilayer Ceramic Capacitor, 10 µF, 10 V, 0603 [1608 Metric], ± 10%, X5R, GRM Series"
			(at 0 0 270)
			(layer "F.Fab")
			(hide yes)
			(effects
				(font
					(size 1.27 1.27)
					(thickness 0.15)
				)
			)
		)
		(property "Author" "Antmicro"
			(at -4 174.35 0)
			(layer "F.Fab")
			(hide yes)
			(effects
				(font
					(size 1 1)
					(thickness 0.15)
				)
			)
		)
		(property "Dielectric" "template_dielectric"
			(at -4 174.35 0)
			(layer "F.Fab")
			(hide yes)
			(effects
				(font
					(size 1 1)
					(thickness 0.15)
				)
			)
		)
		(property "License" "Apache-2.0"
			(at -4 174.35 0)
			(layer "F.Fab")
			(hide yes)
			(effects
				(font
					(size 1 1)
					(thickness 0.15)
				)
			)
		)
		(property "MPN" "GRM188R61A106KE69D"
			(at -4 174.35 0)
			(layer "F.Fab")
			(hide yes)
			(effects
				(font
					(size 1 1)
					(thickness 0.15)
				)
			)
		)
		(property "Manufacturer" "Murata"
			(at -4 174.35 0)
			(layer "F.Fab")
			(hide yes)
			(effects
				(font
					(size 1 1)
					(thickness 0.15)
				)
			)
		)
		(property "Val" "10u"
			(at -4 174.35 0)
			(layer "F.Fab")
			(hide yes)
			(effects
				(font
					(size 1 1)
					(thickness 0.15)
				)
			)
		)
		(property "Voltage" ""
			(at -4 174.35 0)
			(layer "F.Fab")
			(hide yes)
			(effects
				(font
					(size 1 1)
					(thickness 0.15)
				)
			)
		)
		(sheetname "/Power supply/")
		(sheetfile "power-supply.kicad_sch")
		(attr smd)
		(fp_line
			(start -0.15 0.4)
			(end 0.15 0.4)
			(stroke
				(width 0.15)
				(type solid)
			)
			(layer "F.SilkS")
		)
		(fp_line
			(start -0.15 -0.4)
			(end 0.15 -0.4)
			(stroke
				(width 0.15)
				(type solid)
			)
			(layer "F.SilkS")
		)
		(fp_rect
			(start -1.25 -0.65)
			(end 1.25 0.65)
			(stroke
				(width 0.05)
				(type solid)
			)
			(fill no)
			(layer "F.CrtYd")
		)
		(fp_rect
			(start -0.8 -0.4)
			(end 0.8 0.4)
			(stroke
				(width 0.15)
				(type solid)
			)
			(fill no)
			(layer "F.Fab")
		)
		(pad "1" smd roundrect
			(at -0.7 0 270)
			(size 0.8 1)
			(layers "F.Cu" "F.Mask" "F.Paste")
			(roundrect_rratio 0.2)
			(net 1 "GND")
			(pintype "passive")
		)
		(pad "2" smd roundrect
			(at 0.7 0 270)
			(size 0.8 1)
			(layers "F.Cu" "F.Mask" "F.Paste")
			(roundrect_rratio 0.2)
			(net 4 "VCC5V0")
			(pintype "passive")
		)
	)
	(footprint "antmicro-footprints:QFN-8_2x1.5mm"
		(layer "F.Cu")
		(at 87.005 89.435 180)
		(property "Reference" "U13"
			(at 0.265 -2.265 180)
			(layer "F.SilkS")
			(effects
				(font
					(size 0.7 0.7)
					(thickness 0.15)
				)
				(justify left bottom)
			)
		)
		(property "Value" "TPS62823DLCT"
			(at 0 2.2 180)
			(layer "F.Fab")
			(effects
				(font
					(size 0.7 0.7)
					(thickness 0.15)
				)
				(justify left bottom)
			)
		)
		(property "Datasheet" "https://www.ti.com/lit/ds/symlink/tps62823.pdf?ts=1685970309606&ref_url=https%253A%252F%252Fwww.ti.com%252Fproduct%252FTPS62823%252Fpart-details%252FTPS62823DLCT"
			(at 0 0 180)
			(layer "F.Fab")
			(hide yes)
			(effects
				(font
					(size 1.27 1.27)
					(thickness 0.15)
				)
			)
		)
		(property "Description" "DC/DC converter"
			(at 0 0 180)
			(layer "F.Fab")
			(hide yes)
			(effects
				(font
					(size 1.27 1.27)
					(thickness 0.15)
				)
			)
		)
		(property "Author" "Antmicro"
			(at 174.01 178.87 0)
			(layer "F.Fab")
			(hide yes)
			(effects
				(font
					(size 1 1)
					(thickness 0.15)
				)
			)
		)
		(property "License" "Apache-2.0"
			(at 174.01 178.87 0)
			(layer "F.Fab")
			(hide yes)
			(effects
				(font
					(size 1 1)
					(thickness 0.15)
				)
			)
		)
		(property "MPN" "TPS62823DLCT"
			(at 174.01 178.87 0)
			(layer "F.Fab")
			(hide yes)
			(effects
				(font
					(size 1 1)
					(thickness 0.15)
				)
			)
		)
		(property "Manufacturer" "Texas Instruments"
			(at 174.01 178.87 0)
			(layer "F.Fab")
			(hide yes)
			(effects
				(font
					(size 1 1)
					(thickness 0.15)
				)
			)
		)
		(sheetname "/Power supply/")
		(sheetfile "power-supply.kicad_sch")
		(attr smd)
		(fp_line
			(start -0.25 -1.05)
			(end 0.9 -1.05)
			(stroke
				(width 0.15)
				(type solid)
			)
			(layer "F.SilkS")
		)
		(fp_line
			(start -0.9 1.05)
			(end 0.9 1.05)
			(stroke
				(width 0.15)
				(type solid)
			)
			(layer "F.SilkS")
		)
		(fp_circle
			(center -0.9 -1.05)
			(end -0.849 -1.05)
			(stroke
				(width 0.15)
				(type solid)
			)
			(fill yes)
			(layer "F.SilkS")
		)
		(fp_rect
			(start -1.1 -1.25)
			(end 1.1 1.25)
			(stroke
				(width 0.05)
				(type solid)
			)
			(fill no)
			(layer "F.CrtYd")
		)
		(fp_line
			(start 0.998 0.998)
			(end -1 0.998)
			(stroke
				(width 0.15)
				(type solid)
			)
			(layer "F.Fab")
		)
		(fp_line
			(start 0.998 -1)
			(end 0.998 0.998)
			(stroke
				(width 0.15)
				(type solid)
			)
			(layer "F.Fab")
		)
		(fp_line
			(start -0.5 -1)
			(end 0.998 -1)
			(stroke
				(width 0.15)
				(type solid)
			)
			(layer "F.Fab")
		)
		(fp_line
			(start -1 0.998)
			(end -1 -0.5)
			(stroke
				(width 0.15)
				(type solid)
			)
			(layer "F.Fab")
		)
		(fp_line
			(start -1 -0.5)
			(end -0.5 -1)
			(stroke
				(width 0.15)
				(type solid)
			)
			(layer "F.Fab")
		)
		(pad "1" smd rect
			(at -0.677 -0.75 180)
			(size 0.55 0.25)
			(layers "F.Cu" "F.Mask" "F.Paste")
			(net 343 "Net-(U13-EN)")
			(pinfunction "EN")
			(pintype "input")
		)
		(pad "2" smd rect
			(at -0.677 -0.25 180)
			(size 0.55 0.25)
			(layers "F.Cu" "F.Mask" "F.Paste")
			(net 196 "Net-(U13-FB)")
			(pinfunction "FB")
			(pintype "bidirectional")
		)
		(pad "3" smd rect
			(at -0.677 0.248 180)
			(size 0.55 0.25)
			(layers "F.Cu" "F.Mask" "F.Paste")
			(net 1 "GND")
			(pinfunction "AGND")
			(pintype "power_in")
		)
		(pad "4" smd rect
			(at -0.677 0.748 180)
			(size 0.55 0.25)
			(layers "F.Cu" "F.Mask" "F.Paste")
			(net 532 "unconnected-(U13-NC-Pad4)")
			(pinfunction "NC")
			(pintype "no_connect")
		)
		(pad "5" smd rect
			(at 0.675 0.748 180)
			(size 0.55 0.25)
			(layers "F.Cu" "F.Mask" "F.Paste")
			(net 1 "GND")
			(pinfunction "PGND")
			(pintype "power_in")
		)
		(pad "6" smd rect
			(at 0.675 0.248 180)
			(size 0.55 0.25)
			(layers "F.Cu" "F.Mask" "F.Paste")
			(net 290 "Net-(U13-SW)")
			(pinfunction "SW")
			(pintype "bidirectional")
		)
		(pad "7" smd rect
			(at 0.675 -0.25 180)
			(size 0.55 0.25)
			(layers "F.Cu" "F.Mask" "F.Paste")
			(net 4 "VCC5V0")
			(pinfunction "VIN")
			(pintype "power_in")
		)
		(pad "8" smd rect
			(at 0.675 -0.75 180)
			(size 0.55 0.25)
			(layers "F.Cu" "F.Mask" "F.Paste")
			(net 293 "/Power supply/1V35_PG")
			(pinfunction "PG")
			(pintype "output")
		)
	)
)
